(kicad_pcb
	(version 20260206)
	(generator "pcbnew")
	(generator_version "10.0")
	(general
		(thickness 1.6)
		(legacy_teardrops no)
	)
	(paper "A4")
	(title_block
		(title "04192023_DAF0TMB3IC0_F0TG_MB_C_brd_V02_OCP.brd")
		(comment 1 "Grand Teton / footprints 5851-5856 of 8354")
	)
	(layers
		(0 "F.Cu" signal "TOP")
		(4 "In1.Cu" signal "GND")
		(6 "In2.Cu" signal "IN1")
		(8 "In3.Cu" signal "GND1")
		(10 "In4.Cu" signal "IN2")
		(12 "In5.Cu" signal "GND2")
		(14 "In6.Cu" signal "IN3")
		(16 "In7.Cu" signal "GND3")
		(18 "In8.Cu" signal "VCC")
		(20 "In9.Cu" signal "VCC1")
		(22 "In10.Cu" signal "GND4")
		(24 "In11.Cu" signal "IN4")
		(26 "In12.Cu" signal "GND5")
		(28 "In13.Cu" signal "IN5")
		(30 "In14.Cu" signal "GND6")
		(32 "In15.Cu" signal "IN6")
		(34 "In16.Cu" signal "GND7")
		(2 "B.Cu" signal "BOTTOM")
		(9 "F.Adhes" user "F.Adhesive")
		(11 "B.Adhes" user "B.Adhesive")
		(13 "F.Paste" user "Package Geometry/Pastemask Top")
		(15 "B.Paste" user "Package Geometry/Pastemask Bottom")
		(5 "F.SilkS" user "Ref Des/Silkscreen Top")
		(7 "B.SilkS" user "Ref Des/Silkscreen Bottom")
		(1 "F.Mask" user "Board Geometry/Soldermask Top")
		(3 "B.Mask" user "Board Geometry/Soldermask Bottom")
		(17 "Dwgs.User" user "User.Drawings")
		(19 "Cmts.User" user "User.Comments")
		(21 "Eco1.User" user "User.Eco1")
		(23 "Eco2.User" user "User.Eco2")
		(25 "Edge.Cuts" user "Board Geometry/Outline")
		(27 "Margin" user)
		(31 "F.CrtYd" user "Package Geometry/Place Bound Top")
		(29 "B.CrtYd" user "Package Geometry/Place Bound Bottom")
		(35 "F.Fab" user "Ref Des/Assembly Top")
		(33 "B.Fab" user "Ref Des/Assembly Bottom")
	)
	(footprint ""
		(layer "B.Cu")
		(at 105.960164 -262.205216)
		(property "Reference" "C2489"
			(at 0 0 0)
			(layer "B.SilkS")
			(hide yes)
			(effects
				(font
					(size 1.27 1.27)
				)
				(justify mirror)
			)
		)
		(property "Value" ""
			(at 0 0 0)
			(layer "B.Fab")
			(effects
				(font
					(size 1.27 1.27)
				)
				(justify mirror)
			)
		)
		(duplicate_pad_numbers_are_jumpers no)
		(fp_line
			(start -0.7874 -0.4064)
			(end -0.7874 0.4064)
			(stroke
				(width 0.1524)
				(type default)
			)
			(layer "B.SilkS")
		)
		(fp_line
			(start -0.7874 0.4064)
			(end 0.7874 0.4064)
			(stroke
				(width 0.1524)
				(type default)
			)
			(layer "B.SilkS")
		)
		(fp_line
			(start 0.7874 -0.4064)
			(end -0.7874 -0.4064)
			(stroke
				(width 0.1524)
				(type default)
			)
			(layer "B.SilkS")
		)
		(fp_line
			(start 0.7874 0.4064)
			(end 0.7874 -0.4064)
			(stroke
				(width 0.1524)
				(type default)
			)
			(layer "B.SilkS")
		)
		(fp_line
			(start -0.67945 -0.3048)
			(end -0.67945 0.3048)
			(stroke
				(width 0.1)
				(type default)
			)
			(layer "B.Fab")
		)
		(fp_line
			(start -0.67945 0.3048)
			(end -0.120396 0.3048)
			(stroke
				(width 0.1)
				(type default)
			)
			(layer "B.Fab")
		)
		(fp_line
			(start -0.12065 -0.3048)
			(end -0.67945 -0.3048)
			(stroke
				(width 0.1)
				(type default)
			)
			(layer "B.Fab")
		)
		(fp_line
			(start -0.12065 -0.2794)
			(end -0.12065 -0.3048)
			(stroke
				(width 0.1)
				(type default)
			)
			(layer "B.Fab")
		)
		(fp_line
			(start -0.120396 0.2794)
			(end 0.12065 0.2794)
			(stroke
				(width 0.1)
				(type default)
			)
			(layer "B.Fab")
		)
		(fp_line
			(start -0.120396 0.3048)
			(end -0.120396 0.2794)
			(stroke
				(width 0.1)
				(type default)
			)
			(layer "B.Fab")
		)
		(fp_line
			(start 0.12065 -0.305054)
			(end 0.12065 -0.2794)
			(stroke
				(width 0.1)
				(type default)
			)
			(layer "B.Fab")
		)
		(fp_line
			(start 0.12065 -0.2794)
			(end -0.12065 -0.2794)
			(stroke
				(width 0.1)
				(type default)
			)
			(layer "B.Fab")
		)
		(fp_line
			(start 0.12065 0.2794)
			(end 0.12065 0.3048)
			(stroke
				(width 0.1)
				(type default)
			)
			(layer "B.Fab")
		)
		(fp_line
			(start 0.12065 0.3048)
			(end 0.67945 0.3048)
			(stroke
				(width 0.1)
				(type default)
			)
			(layer "B.Fab")
		)
		(fp_line
			(start 0.67945 -0.305054)
			(end 0.12065 -0.305054)
			(stroke
				(width 0.1)
				(type default)
			)
			(layer "B.Fab")
		)
		(fp_line
			(start 0.67945 0.3048)
			(end 0.67945 -0.305054)
			(stroke
				(width 0.1)
				(type default)
			)
			(layer "B.Fab")
		)
		(pad "1" smd circle
			(at 0.40005 0 180)
			(size 0 0)
			(layers "B.Cu" "B.Mask" "B.Paste")
			(net "PVDD11_S3_P1")
		)
		(pad "2" smd circle
			(at -0.40005 0 180)
			(size 0 0)
			(layers "B.Cu" "B.Mask" "B.Paste")
			(net "GND")
		)
	)
	(footprint ""
		(layer "B.Cu")
		(at 116.225828 -256.012442 -90)
		(property "Reference" "C2458"
			(at 0 0 90)
			(layer "B.SilkS")
			(hide yes)
			(effects
				(font
					(size 1.27 1.27)
				)
				(justify mirror)
			)
		)
		(property "Value" ""
			(at 0 0 90)
			(layer "B.Fab")
			(effects
				(font
					(size 1.27 1.27)
				)
				(justify mirror)
			)
		)
		(duplicate_pad_numbers_are_jumpers no)
		(fp_line
			(start -0.7874 0.4064)
			(end 0.7874 0.4064)
			(stroke
				(width 0.1524)
				(type default)
			)
			(layer "B.SilkS")
		)
		(fp_line
			(start 0.7874 0.4064)
			(end 0.7874 -0.4064)
			(stroke
				(width 0.1524)
				(type default)
			)
			(layer "B.SilkS")
		)
		(fp_line
			(start -0.7874 -0.4064)
			(end -0.7874 0.4064)
			(stroke
				(width 0.1524)
				(type default)
			)
			(layer "B.SilkS")
		)
		(fp_line
			(start 0.7874 -0.4064)
			(end -0.7874 -0.4064)
			(stroke
				(width 0.1524)
				(type default)
			)
			(layer "B.SilkS")
		)
		(fp_line
			(start -0.67945 0.3048)
			(end -0.120396 0.3048)
			(stroke
				(width 0.1)
				(type default)
			)
			(layer "B.Fab")
		)
		(fp_line
			(start -0.120396 0.3048)
			(end -0.120396 0.2794)
			(stroke
				(width 0.1)
				(type default)
			)
			(layer "B.Fab")
		)
		(fp_line
			(start 0.12065 0.3048)
			(end 0.67945 0.3048)
			(stroke
				(width 0.1)
				(type default)
			)
			(layer "B.Fab")
		)
		(fp_line
			(start 0.67945 0.3048)
			(end 0.67945 -0.305054)
			(stroke
				(width 0.1)
				(type default)
			)
			(layer "B.Fab")
		)
		(fp_line
			(start -0.120396 0.2794)
			(end 0.12065 0.2794)
			(stroke
				(width 0.1)
				(type default)
			)
			(layer "B.Fab")
		)
		(fp_line
			(start 0.12065 0.2794)
			(end 0.12065 0.3048)
			(stroke
				(width 0.1)
				(type default)
			)
			(layer "B.Fab")
		)
		(fp_line
			(start -0.12065 -0.2794)
			(end -0.12065 -0.3048)
			(stroke
				(width 0.1)
				(type default)
			)
			(layer "B.Fab")
		)
		(fp_line
			(start 0.12065 -0.2794)
			(end -0.12065 -0.2794)
			(stroke
				(width 0.1)
				(type default)
			)
			(layer "B.Fab")
		)
		(fp_line
			(start -0.67945 -0.3048)
			(end -0.67945 0.3048)
			(stroke
				(width 0.1)
				(type default)
			)
			(layer "B.Fab")
		)
		(fp_line
			(start -0.12065 -0.3048)
			(end -0.67945 -0.3048)
			(stroke
				(width 0.1)
				(type default)
			)
			(layer "B.Fab")
		)
		(fp_line
			(start 0.12065 -0.305054)
			(end 0.12065 -0.2794)
			(stroke
				(width 0.1)
				(type default)
			)
			(layer "B.Fab")
		)
		(fp_line
			(start 0.67945 -0.305054)
			(end 0.12065 -0.305054)
			(stroke
				(width 0.1)
				(type default)
			)
			(layer "B.Fab")
		)
		(pad "1" smd circle
			(at 0.40005 0 90)
			(size 0 0)
			(layers "B.Cu" "B.Mask" "B.Paste")
			(net "PVDDCR_SOC_P1")
		)
		(pad "2" smd circle
			(at -0.40005 0 90)
			(size 0 0)
			(layers "B.Cu" "B.Mask" "B.Paste")
			(net "GND")
		)
	)
	(footprint ""
		(layer "B.Cu")
		(at 164.07257 -120.364758)
		(property "Reference" "R6093"
			(at 0 0 0)
			(layer "B.SilkS")
			(hide yes)
			(effects
				(font
					(size 1.27 1.27)
				)
				(justify mirror)
			)
		)
		(property "Value" ""
			(at 0 0 0)
			(layer "B.Fab")
			(effects
				(font
					(size 1.27 1.27)
				)
				(justify mirror)
			)
		)
		(duplicate_pad_numbers_are_jumpers no)
		(fp_line
			(start -0.7874 -0.4064)
			(end -0.7874 0.4064)
			(stroke
				(width 0.1524)
				(type default)
			)
			(layer "B.SilkS")
		)
		(fp_line
			(start -0.7874 0.4064)
			(end 0.7874 0.4064)
			(stroke
				(width 0.1524)
				(type default)
			)
			(layer "B.SilkS")
		)
		(fp_line
			(start 0.7874 -0.4064)
			(end -0.7874 -0.4064)
			(stroke
				(width 0.1524)
				(type default)
			)
			(layer "B.SilkS")
		)
		(fp_line
			(start 0.7874 0.4064)
			(end 0.7874 -0.4064)
			(stroke
				(width 0.1524)
				(type default)
			)
			(layer "B.SilkS")
		)
		(fp_line
			(start -0.67945 -0.3048)
			(end -0.67945 0.3048)
			(stroke
				(width 0.1)
				(type default)
			)
			(layer "B.Fab")
		)
		(fp_line
			(start -0.67945 0.3048)
			(end -0.120396 0.3048)
			(stroke
				(width 0.1)
				(type default)
			)
			(layer "B.Fab")
		)
		(fp_line
			(start -0.12065 -0.3048)
			(end -0.67945 -0.3048)
			(stroke
				(width 0.1)
				(type default)
			)
			(layer "B.Fab")
		)
		(fp_line
			(start -0.12065 -0.2794)
			(end -0.12065 -0.3048)
			(stroke
				(width 0.1)
				(type default)
			)
			(layer "B.Fab")
		)
		(fp_line
			(start -0.120396 0.2794)
			(end 0.12065 0.2794)
			(stroke
				(width 0.1)
				(type default)
			)
			(layer "B.Fab")
		)
		(fp_line
			(start -0.120396 0.3048)
			(end -0.120396 0.2794)
			(stroke
				(width 0.1)
				(type default)
			)
			(layer "B.Fab")
		)
		(fp_line
			(start 0.12065 -0.305054)
			(end 0.12065 -0.2794)
			(stroke
				(width 0.1)
				(type default)
			)
			(layer "B.Fab")
		)
		(fp_line
			(start 0.12065 -0.2794)
			(end -0.12065 -0.2794)
			(stroke
				(width 0.1)
				(type default)
			)
			(layer "B.Fab")
		)
		(fp_line
			(start 0.12065 0.2794)
			(end 0.12065 0.3048)
			(stroke
				(width 0.1)
				(type default)
			)
			(layer "B.Fab")
		)
		(fp_line
			(start 0.12065 0.3048)
			(end 0.67945 0.3048)
			(stroke
				(width 0.1)
				(type default)
			)
			(layer "B.Fab")
		)
		(fp_line
			(start 0.67945 -0.305054)
			(end 0.12065 -0.305054)
			(stroke
				(width 0.1)
				(type default)
			)
			(layer "B.Fab")
		)
		(fp_line
			(start 0.67945 0.3048)
			(end 0.67945 -0.305054)
			(stroke
				(width 0.1)
				(type default)
			)
			(layer "B.Fab")
		)
		(pad "1" smd circle
			(at 0.40005 0 180)
			(size 0 0)
			(layers "B.Cu" "B.Mask" "B.Paste")
			(net "SCM_SYS_PWROK_R")
		)
		(pad "2" smd circle
			(at -0.40005 0 180)
			(size 0 0)
			(layers "B.Cu" "B.Mask" "B.Paste")
			(net "SCM_SYS_PWROK_R2")
		)
	)
	(footprint ""
		(layer "B.Cu")
		(at 311.387236 -197.836028 -90)
		(property "Reference" "R6082"
			(at 0 0 90)
			(layer "B.SilkS")
			(hide yes)
			(effects
				(font
					(size 1.27 1.27)
				)
				(justify mirror)
			)
		)
		(property "Value" ""
			(at 0 0 90)
			(layer "B.Fab")
			(effects
				(font
					(size 1.27 1.27)
				)
				(justify mirror)
			)
		)
		(duplicate_pad_numbers_are_jumpers no)
		(fp_line
			(start -0.7874 0.4064)
			(end 0.7874 0.4064)
			(stroke
				(width 0.1524)
				(type default)
			)
			(layer "B.SilkS")
		)
		(fp_line
			(start 0.7874 0.4064)
			(end 0.7874 -0.4064)
			(stroke
				(width 0.1524)
				(type default)
			)
			(layer "B.SilkS")
		)
		(fp_line
			(start -0.7874 -0.4064)
			(end -0.7874 0.4064)
			(stroke
				(width 0.1524)
				(type default)
			)
			(layer "B.SilkS")
		)
		(fp_line
			(start 0.7874 -0.4064)
			(end -0.7874 -0.4064)
			(stroke
				(width 0.1524)
				(type default)
			)
			(layer "B.SilkS")
		)
		(fp_line
			(start -0.67945 0.3048)
			(end -0.120396 0.3048)
			(stroke
				(width 0.1)
				(type default)
			)
			(layer "B.Fab")
		)
		(fp_line
			(start -0.120396 0.3048)
			(end -0.120396 0.2794)
			(stroke
				(width 0.1)
				(type default)
			)
			(layer "B.Fab")
		)
		(fp_line
			(start 0.12065 0.3048)
			(end 0.67945 0.3048)
			(stroke
				(width 0.1)
				(type default)
			)
			(layer "B.Fab")
		)
		(fp_line
			(start 0.67945 0.3048)
			(end 0.67945 -0.305054)
			(stroke
				(width 0.1)
				(type default)
			)
			(layer "B.Fab")
		)
		(fp_line
			(start -0.120396 0.2794)
			(end 0.12065 0.2794)
			(stroke
				(width 0.1)
				(type default)
			)
			(layer "B.Fab")
		)
		(fp_line
			(start 0.12065 0.2794)
			(end 0.12065 0.3048)
			(stroke
				(width 0.1)
				(type default)
			)
			(layer "B.Fab")
		)
		(fp_line
			(start -0.12065 -0.2794)
			(end -0.12065 -0.3048)
			(stroke
				(width 0.1)
				(type default)
			)
			(layer "B.Fab")
		)
		(fp_line
			(start 0.12065 -0.2794)
			(end -0.12065 -0.2794)
			(stroke
				(width 0.1)
				(type default)
			)
			(layer "B.Fab")
		)
		(fp_line
			(start -0.67945 -0.3048)
			(end -0.67945 0.3048)
			(stroke
				(width 0.1)
				(type default)
			)
			(layer "B.Fab")
		)
		(fp_line
			(start -0.12065 -0.3048)
			(end -0.67945 -0.3048)
			(stroke
				(width 0.1)
				(type default)
			)
			(layer "B.Fab")
		)
		(fp_line
			(start 0.12065 -0.305054)
			(end 0.12065 -0.2794)
			(stroke
				(width 0.1)
				(type default)
			)
			(layer "B.Fab")
		)
		(fp_line
			(start 0.67945 -0.305054)
			(end 0.12065 -0.305054)
			(stroke
				(width 0.1)
				(type default)
			)
			(layer "B.Fab")
		)
		(pad "1" smd circle
			(at 0.40005 0 90)
			(size 0 0)
			(layers "B.Cu" "B.Mask" "B.Paste")
			(net "PVDD11_S3_P0")
		)
		(pad "2" smd circle
			(at -0.40005 0 90)
			(size 0 0)
			(layers "B.Cu" "B.Mask" "B.Paste")
			(net "SMB_CPU0_2_SDA")
		)
	)
	(footprint ""
		(layer "B.Cu")
		(at 255.757426 -325.056754 180)
		(property "Reference" "C1085"
			(at 0 0 0)
			(layer "B.SilkS")
			(hide yes)
			(effects
				(font
					(size 1.27 1.27)
				)
				(justify mirror)
			)
		)
		(property "Value" ""
			(at 0 0 0)
			(layer "B.Fab")
			(effects
				(font
					(size 1.27 1.27)
				)
				(justify mirror)
			)
		)
		(duplicate_pad_numbers_are_jumpers no)
		(fp_line
			(start 0.7874 0.4064)
			(end 0.7874 -0.4064)
			(stroke
				(width 0.1524)
				(type default)
			)
			(layer "B.SilkS")
		)
		(fp_line
			(start 0.7874 -0.4064)
			(end -0.7874 -0.4064)
			(stroke
				(width 0.1524)
				(type default)
			)
			(layer "B.SilkS")
		)
		(fp_line
			(start -0.7874 0.4064)
			(end 0.7874 0.4064)
			(stroke
				(width 0.1524)
				(type default)
			)
			(layer "B.SilkS")
		)
		(fp_line
			(start -0.7874 -0.4064)
			(end -0.7874 0.4064)
			(stroke
				(width 0.1524)
				(type default)
			)
			(layer "B.SilkS")
		)
		(fp_line
			(start 0.67945 0.3048)
			(end 0.67945 -0.305054)
			(stroke
				(width 0.1)
				(type default)
			)
			(layer "B.Fab")
		)
		(fp_line
			(start 0.67945 -0.305054)
			(end 0.12065 -0.305054)
			(stroke
				(width 0.1)
				(type default)
			)
			(layer "B.Fab")
		)
		(fp_line
			(start 0.12065 0.3048)
			(end 0.67945 0.3048)
			(stroke
				(width 0.1)
				(type default)
			)
			(layer "B.Fab")
		)
		(fp_line
			(start 0.12065 0.2794)
			(end 0.12065 0.3048)
			(stroke
				(width 0.1)
				(type default)
			)
			(layer "B.Fab")
		)
		(fp_line
			(start 0.12065 -0.2794)
			(end -0.12065 -0.2794)
			(stroke
				(width 0.1)
				(type default)
			)
			(layer "B.Fab")
		)
		(fp_line
			(start 0.12065 -0.305054)
			(end 0.12065 -0.2794)
			(stroke
				(width 0.1)
				(type default)
			)
			(layer "B.Fab")
		)
		(fp_line
			(start -0.120396 0.3048)
			(end -0.120396 0.2794)
			(stroke
				(width 0.1)
				(type default)
			)
			(layer "B.Fab")
		)
		(fp_line
			(start -0.120396 0.2794)
			(end 0.12065 0.2794)
			(stroke
				(width 0.1)
				(type default)
			)
			(layer "B.Fab")
		)
		(fp_line
			(start -0.12065 -0.2794)
			(end -0.12065 -0.3048)
			(stroke
				(width 0.1)
				(type default)
			)
			(layer "B.Fab")
		)
		(fp_line
			(start -0.12065 -0.3048)
			(end -0.67945 -0.3048)
			(stroke
				(width 0.1)
				(type default)
			)
			(layer "B.Fab")
		)
		(fp_line
			(start -0.67945 0.3048)
			(end -0.120396 0.3048)
			(stroke
				(width 0.1)
				(type default)
			)
			(layer "B.Fab")
		)
		(fp_line
			(start -0.67945 -0.3048)
			(end -0.67945 0.3048)
			(stroke
				(width 0.1)
				(type default)
			)
			(layer "B.Fab")
		)
		(pad "1" smd circle
			(at 0.40005 0)
			(size 0 0)
			(layers "B.Cu" "B.Mask" "B.Paste")
			(net "P5V_AUX_ADC_MAM")
		)
		(pad "2" smd circle
			(at -0.40005 0)
			(size 0 0)
			(layers "B.Cu" "B.Mask" "B.Paste")
			(net "GND")
		)
	)
	(footprint ""
		(layer "B.Cu")
		(at 157.81909 -390.560052 90)
		(property "Reference" "C408"
			(at 0 0 90)
			(layer "B.SilkS")
			(hide yes)
			(effects
				(font
					(size 1.27 1.27)
				)
				(justify mirror)
			)
		)
		(property "Value" ""
			(at 0 0 90)
			(layer "B.Fab")
			(effects
				(font
					(size 1.27 1.27)
				)
				(justify mirror)
			)
		)
		(duplicate_pad_numbers_are_jumpers no)
		(fp_line
			(start 0.7874 -0.4064)
			(end -0.7874 -0.4064)
			(stroke
				(width 0.1524)
				(type default)
			)
			(layer "B.SilkS")
		)
		(fp_line
			(start -0.7874 -0.4064)
			(end -0.7874 0.4064)
			(stroke
				(width 0.1524)
				(type default)
			)
			(layer "B.SilkS")
		)
		(fp_line
			(start 0.7874 0.4064)
			(end 0.7874 -0.4064)
			(stroke
				(width 0.1524)
				(type default)
			)
			(layer "B.SilkS")
		)
		(fp_line
			(start -0.7874 0.4064)
			(end 0.7874 0.4064)
			(stroke
				(width 0.1524)
				(type default)
			)
			(layer "B.SilkS")
		)
		(fp_line
			(start 0.67945 -0.305054)
			(end 0.12065 -0.305054)
			(stroke
				(width 0.1)
				(type default)
			)
			(layer "B.Fab")
		)
		(fp_line
			(start 0.12065 -0.305054)
			(end 0.12065 -0.2794)
			(stroke
				(width 0.1)
				(type default)
			)
			(layer "B.Fab")
		)
		(fp_line
			(start -0.12065 -0.3048)
			(end -0.67945 -0.3048)
			(stroke
				(width 0.1)
				(type default)
			)
			(layer "B.Fab")
		)
		(fp_line
			(start -0.67945 -0.3048)
			(end -0.67945 0.3048)
			(stroke
				(width 0.1)
				(type default)
			)
			(layer "B.Fab")
		)
		(fp_line
			(start 0.12065 -0.2794)
			(end -0.12065 -0.2794)
			(stroke
				(width 0.1)
				(type default)
			)
			(layer "B.Fab")
		)
		(fp_line
			(start -0.12065 -0.2794)
			(end -0.12065 -0.3048)
			(stroke
				(width 0.1)
				(type default)
			)
			(layer "B.Fab")
		)
		(fp_line
			(start 0.12065 0.2794)
			(end 0.12065 0.3048)
			(stroke
				(width 0.1)
				(type default)
			)
			(layer "B.Fab")
		)
		(fp_line
			(start -0.120396 0.2794)
			(end 0.12065 0.2794)
			(stroke
				(width 0.1)
				(type default)
			)
			(layer "B.Fab")
		)
		(fp_line
			(start 0.67945 0.3048)
			(end 0.67945 -0.305054)
			(stroke
				(width 0.1)
				(type default)
			)
			(layer "B.Fab")
		)
		(fp_line
			(start 0.12065 0.3048)
			(end 0.67945 0.3048)
			(stroke
				(width 0.1)
				(type default)
			)
			(layer "B.Fab")
		)
		(fp_line
			(start -0.120396 0.3048)
			(end -0.120396 0.2794)
			(stroke
				(width 0.1)
				(type default)
			)
			(layer "B.Fab")
		)
		(fp_line
			(start -0.67945 0.3048)
			(end -0.120396 0.3048)
			(stroke
				(width 0.1)
				(type default)
			)
			(layer "B.Fab")
		)
		(pad "1" smd circle
			(at 0.40005 0 270)
			(size 0 0)
			(layers "B.Cu" "B.Mask" "B.Paste")
			(net "P0V9_CPU1_RT_2D")
		)
		(pad "2" smd circle
			(at -0.40005 0 270)
			(size 0 0)
			(layers "B.Cu" "B.Mask" "B.Paste")
			(net "GND")
		)
	)
)
